FILE_TYPE = CONNECTIVITY;
{Allegro Design Entry HDL 16.6-p007 (v16-6-112F) 10/10/2012}
"PAGE_NUMBER" = 247;
0"NC";
1"P3V3_STBY\g";
2"GND\g";
3"GND\g";
4"P3V3_STBY\g";
5"P3V3_STBY\g";
6"GND\g";
7"P3V3_STBY\g";
8"GND\g";
9"GND\g";
10"P3V3_STBY\g";
11"GND\g";
12"P3V3_STBY\g";
13"GND\g";
14"P3V3_STBY\g";
15"GND\g";
16"P3V3_STBY\g";
17"GND\g";
18"P3V3_STBY\g";
19"GND\g";
20"GND\g";
21"SMB_HOST_STBY_LVC3_SDA_R3";
22"RST_PLTRST_N";
23"PWRGD_SYS_PWROK";
24"FP_PWR_BTN_R_N";
25"FM_DEBUG_RST_BTN_N";
26"SMB_DEBUG_STBY_LVC3_SCL";
27"SMB_DEBUG_STBY_LVC3_SDA";
28"PCA9555_INT_N";
29"PWRGD_DSW_PWROK";
30"FM_CPU_CATERR_MSMI_LVT3_N";
31"FM_UART_SWITCH_N";
32"SMB_HOST_STBY_LVC3_SDA";
33"FM_SLPS3_N";
34"PU_ID_EEPROM_A0";
35"SMB_HOST_STBY_LVC3_SCL_R3";
36"PD_ID_EEPROM_WP";
37"PCA9555_A2";
38"PCA9555_A1";
39"LED_POSTCODE_0_R";
40"PCA9555_A0";
41"FM_CPU_MSMI_LVT3_N";
42"FM_CPU_CATERR_LVT3_N";
43"PCA9555_A1";
44"PCA9555_A2";
45"LED_POSTCODE_2_R";
46"LED_POSTCODE_1_R";
47"LED_POSTCODE_7_R";
48"LED_POSTCODE_4_R";
49"LED_POSTCODE_5_R";
50"LED_POSTCODE_3_R";
51"PCA9555_A0";
52"LED_POSTCODE_6_R";
53"PCA9555_INT_N";
54"SMB_DEBUG_STBY_LVC3_SCL";
55"SMB_DEBUG_STBY_LVC3_SDA";
56"SMB_PMBUS_BMC_STBY_LVC3_SDA_R1"CDS_PHYS_NET_NAME"SMB_PMBUS_BMC_STBY_LVC3_SDA_R1";
57"SMB_PMBUS_BMC_STBY_LVC3_SCL_R1"CDS_PHYS_NET_NAME"SMB_PMBUS_BMC_STBY_LVC3_SCL_R1";
58"SMB_PMBUS_BMC_STBY_LVC3_SDA_R1";
59"SMB_PMBUS_BMC_STBY_LVC3_SCL_R1";
60"HSC_SMBUS_SWITCH_EN";
61"SMB_BMC_PMBUS_STBY_LVC3_SCL"CDS_PHYS_NET_NAME"SMB_BMC_PMBUS_STBY_LVC3_SCL";
62"SMB_BMC_PMBUS_STBY_LVC3_SDA"CDS_PHYS_NET_NAME"SMB_BMC_PMBUS_STBY_LVC3_SDA";
63"HSC_SMBUS_SWITCH_EN";
64"SMB_HOST_STBY_LVC3_SCL";
%"RES"
"2","(-7450,3350)","2","mstr_discrete","I1";
;
CDS_SEC"1"
CDS_LOCATION"R6W10"
PART_NUMBER"G21796-072"
MATERIAL"CHIP"
WATTAGE"1/16W"
TOLERANCE"1%"
VALUE"4.75K"
LOCATION"R6W10"
PACK_TYPE"0402"
CDS_LIB"mstr_discrete"
ROOM"CPU_FANS"
BOM_COST"SM_THERM"
SEC_TYPE"0402"
SEC"1";
"A"
$PN"1"7;
"B"
$PN"2"53;
%"RES"
"2","(-7550,1950)","2","mstr_discrete","I100";
;
CDS_SEC"1"
CDS_LOCATION"R6W24"
PACK_TYPE"0402"
PART_NUMBER"G21796-072"
TOLERANCE"1%"
WATTAGE"1/16W"
MATERIAL"CHIP"
LOCATION"R6W24"
VALUE"4.75K"
SEC_TYPE"0402"
SEC"1"
ROOM"CPU_FANS"
BOM_COST"SM_THERM"
CDS_LIB"mstr_discrete";
"A"
$PN"1"1;
"B"
$PN"2"58;
%"RES"
"2","(-7200,1950)","2","mstr_discrete","I101";
;
CDS_SEC"1"
CDS_LOCATION"R6W25"
PACK_TYPE"0402"
WATTAGE"1/16W"
MATERIAL"CHIP"
PART_NUMBER"G21796-072"
TOLERANCE"1%"
VALUE"4.75K"
LOCATION"R6W25"
SEC_TYPE"0402"
SEC"1"
CDS_LIB"mstr_discrete"
ROOM"CPU_FANS"
BOM_COST"SM_THERM";
"A"
$PN"1"1;
"B"
$PN"2"59;
%"P3V3_STBY"
"1","(-7550,2250)","0","mstr_symbols","I102";
;
HDL_POWER"P3V3_STBY"
BODY_TYPE"PLUMBING"
SIZE"1B"
VOLTAGE"3.3V"
CDS_LIB"mstr_symbols";
"G\NAC"1;
%"GND"
"1","(-7250,1050)","0","mstr_symbols","I104";
;
HDL_POWER"GND"
BODY_TYPE"PLUMBING"
VOLTAGE"0"
CDS_LIB"mstr_symbols"
SIZE"1B"
BOM_COST"NT_BASE_VRD"
ROOM"P2V5_LAN_AUX_VR";
"A\NAC"2;
%"CAP_A"
"1","(-7250,1250)","0","dev_discrete","I105";
;
PACK_TYPE"0402V"
MATERIAL"X7R"
TOLERANCE"10%"
VOLTAGE"16V"
VALUE"0.1UF"
LOCATION"C6W4"
PART_NUMBER"A36096-030"
CDS_LOCATION"C6W4"
CDS_SEC"1"
ROOM"SMB_PE_HP_CPU1"
SEC_TYPE"0402V"
SEC"1"
CDS_LIB"dev_discrete";
"B"
$PN"2"2;
"A"
$PN"1"5;
%"CAP_A"
"1","(-5500,1250)","2","dev_discrete","I107";
;
VALUE"0.1UF"
TOLERANCE"10%"
PART_NUMBER"A36096-030"
LOCATION"C6W2"
VOLTAGE"16V"
MATERIAL"X7R"
PACK_TYPE"0402V"
CDS_LOCATION"C6W2"
SEC_TYPE"0402V"
SEC"1"
CDS_LIB"dev_discrete"
ROOM"SMB_PE_HP_CPU1"
CDS_SEC"1";
"B"
$PN"2"3;
"A"
$PN"1"4;
%"GND"
"1","(-5500,1050)","0","mstr_symbols","I108";
;
HDL_POWER"GND"
BODY_TYPE"PLUMBING"
ROOM"P2V5_LAN_AUX_VR"
BOM_COST"NT_BASE_VRD"
SIZE"1B"
CDS_LIB"mstr_symbols"
VOLTAGE"0";
"A\NAC"3;
%"P3V3_STBY"
"1","(-5950,1500)","0","mstr_symbols","I109";
;
HDL_POWER"P3V3_STBY"
BODY_TYPE"PLUMBING"
SIZE"1B"
CDS_LIB"mstr_symbols"
VOLTAGE"3.3V";
"G\NAC"4;
%"P3V3_STBY"
"1","(-6900,1500)","0","mstr_symbols","I111";
;
HDL_POWER"P3V3_STBY"
BODY_TYPE"PLUMBING"
CDS_LIB"mstr_symbols"
VOLTAGE"3.3V"
SIZE"1B";
"G\NAC"5;
%"RES"
"2","(-6850,1950)","2","mstr_discrete","I112";
;
CDS_SEC"1"
CDS_LOCATION"R6W28"
PACK_TYPE"0402"
MATERIAL"CHIP"
PART_NUMBER"G21796-072"
TOLERANCE"1%"
WATTAGE"1/16W"
VALUE"4.75K"
LOCATION"R6W28"
SEC_TYPE"0402"
SEC"1"
BOM_COST"SM_THERM"
ROOM"CPU_FANS"
CDS_LIB"mstr_discrete";
"A"
$PN"1"1;
"B"
$PN"2"60;
%"TCA9517DGKR-GP"
"1","(-6375,925)","0","w_hdl","I118";
;
CDS_SEC"1"
CDS_LOCATION"U6W2"
LOCATION"U6W2"
VALUE"TCA9517DGKR-GP"
PACK_TYPE"DISCRET-G8"
SEC"1"
SEC_TYPE"DISCRET-G8"
PART_NUMBER"071.09517.0009"
CDS_LIB"w_hdl"
CDS_LMAN_SYM_OUTLINE"-175,175,175,-175";
"EN"
$PN"5"63;
"SDAB"
$PN"6"62;
"SCLB"
$PN"7"61;
"VCCB"
$PN"8"4;
"GND"
$PN"4"6;
"SDAA"
$PN"3"56;
"SCLA"
$PN"2"57;
"VCCA"
$PN"1"5;
%"GND"
"1","(-6750,750)","0","mstr_symbols","I119";
;
HDL_POWER"GND"
BODY_TYPE"PLUMBING"
VOLTAGE"0"
CDS_LIB"mstr_symbols"
SIZE"1B"
BOM_COST"NT_BASE_VRD"
ROOM"P2V5_LAN_AUX_VR";
"A\NAC"6;
%"P3V3_STBY"
"1","(-7450,3700)","0","mstr_symbols","I12";
;
HDL_POWER"P3V3_STBY"
BODY_TYPE"PLUMBING"
CDS_LIB"mstr_symbols"
SIZE"1B"
VOLTAGE"3.3V";
"G\NAC"7;
%"TCA9555PWR-GP"
"1","(-3950,3675)","0","w_hdl","I120";
;
CDS_SEC"1"
CDS_LOCATION"U6W1"
VALUE"TCA9555PWR-GP"
LOCATION"U6W1"
PACK_TYPE"DISCRET-GC1"
SEC"1"
SEC_TYPE"DISCRET-GC1"
PART_NUMBER"071.09555.000W"
CDS_LIB"w_hdl"
CDS_LMAN_SYM_OUTLINE"-200,475,200,-475";
"P17"
$PN"20"31;
"P16"
$PN"19"33;
"P15"
$PN"18"30;
"P14"
$PN"17"29;
"P13"
$PN"16"22;
"P12"
$PN"15"23;
"P11"
$PN"14"24;
"P10"
$PN"13"25;
"A0"
$PN"21"51;
"SCL"
$PN"22"26;
"SDA"
$PN"23"27;
"VCC"
$PN"24"10;
"GND"
$PN"12"8;
"P07"
$PN"11"47;
"P06"
$PN"10"52;
"P05"
$PN"9"49;
"P04"
$PN"8"48;
"P03"
$PN"7"50;
"P02"
$PN"6"45;
"P01"
$PN"5"46;
"P00"
$PN"4"39;
"A2"
$PN"3"37;
"A1"
$PN"2"38;
"INT# \B"
$PN"1"28;
%"GND"
"1","(-3550,3225)","0","mstr_symbols","I121";
;
VOLTAGE"0.0V"
SIZE"1B"
CDS_LIB"mstr_symbols"
BODY_TYPE"PLUMBING"
HDL_POWER"GND";
"A\NAC"8;
%"GND"
"1","(-5900,3450)","0","mstr_symbols","I13";
;
HDL_POWER"GND"
BODY_TYPE"PLUMBING"
SIZE"1B"
CDS_LIB"mstr_symbols"
VOLTAGE"0.0V";
"A\NAC"9;
%"P3V3_STBY"
"1","(-5200,4450)","0","mstr_symbols","I148";
;
HDL_POWER"P3V3_STBY"
BODY_TYPE"PLUMBING"
VOLTAGE"3.3V"
SIZE"1B"
CDS_LIB"mstr_symbols";
"G\NAC"10;
%"GND"
"1","(-5200,4000)","0","mstr_symbols","I150";
;
HDL_POWER"GND"
BODY_TYPE"PLUMBING"
CDS_LIB"mstr_symbols"
SIZE"1B"
VOLTAGE"0.0V";
"A\NAC"11;
%"CAP_A"
"1","(-5200,4200)","0","dev_discrete","I151";
;
LOCATION"C6W1"
VALUE"0.1UF"
VOLTAGE"16V"
TOLERANCE"10%"
MATERIAL"X7R"
PART_NUMBER"A36096-030"
PACK_TYPE"0402V"
CDS_LIB"dev_discrete"
CDS_SEC"1"
ROOM"VDDQ_KLM_PWR_VR"
SEC_TYPE"0402V"
SEC"1"
CDS_LOCATION"C6W1";
"B"
$PN"2"11;
"A"
$PN"1"10;
%"P3V3_STBY"
"1","(-1750,3950)","0","mstr_symbols","I156";
;
HDL_POWER"P3V3_STBY"
BODY_TYPE"PLUMBING"
VOLTAGE"3.3V"
SIZE"1B"
CDS_LIB"mstr_symbols";
"G\NAC"12;
%"DIODE"
"1","(-1350,3650)","6","mstr_discrete","I157";
;
CDS_SEC"1"
VALUE"BAT54WS"
MATERIAL"IC"
LOCATION"CR6W1"
PART_NUMBER"C73510-001"
PACK_TYPE"SMLF"
CDS_LOCATION"CR6W1"
SEC"1"
SEC_TYPE"SMLF"
CDS_LIB"mstr_discrete";
"C"
$PN"1"42;
"A"
$PN"2"30;
%"DIODE"
"1","(-1350,3450)","6","mstr_discrete","I158";
;
CDS_SEC"1"
MATERIAL"IC"
PACK_TYPE"SMLF"
VALUE"BAT54WS"
PART_NUMBER"C73510-001"
LOCATION"CR6W2"
CDS_LOCATION"CR6W2"
SEC"1"
SEC_TYPE"SMLF"
CDS_LIB"mstr_discrete";
"C"
$PN"1"41;
"A"
$PN"2"30;
%"RES"
"2","(-6600,4200)","2","mstr_discrete","I159";
;
CDS_SEC"1"
CDS_LOCATION"R6W4"
VALUE"4.75K"
LOCATION"R6W4"
TOLERANCE"1%"
WATTAGE"1/16W"
PART_NUMBER"G21796-072"
MATERIAL"CHIP"
PACK_TYPE"0402"
SEC_TYPE"0402"
SEC"1"
BOM_COST"SM_THERM"
ROOM"CPU_FANS"
CDS_LIB"mstr_discrete";
"A"
$PN"1"14;
"B"
$PN"2"44;
%"RES"
"2","(-6250,4200)","2","mstr_discrete","I160";
;
CDS_SEC"1"
CDS_LOCATION"R6W5"
LOCATION"R6W5"
VALUE"4.75K"
TOLERANCE"1%"
WATTAGE"1/16W"
MATERIAL"CHIP"
PART_NUMBER"G21796-072"
PACK_TYPE"0402"
SEC_TYPE"0402"
SEC"1"
BOM_COST"SM_THERM"
ROOM"CPU_FANS"
CDS_LIB"mstr_discrete";
"A"
$PN"1"14;
"B"
$PN"2"43;
%"RES"
"2","(-5900,4200)","2","mstr_discrete","I161";
;
CDS_SEC"1"
CDS_LOCATION"R6W6"
PART_NUMBER"G21796-072"
LOCATION"R6W6"
WATTAGE"1/16W"
VALUE"4.75K"
PACK_TYPE"0402"
MATERIAL"CHIP"
TOLERANCE"1%"
SEC_TYPE"0402"
SEC"1"
ROOM"CPU_FANS"
BOM_COST"SM_THERM"
CDS_LIB"mstr_discrete";
"A"
$PN"1"14;
"B"
$PN"2"40;
%"RES"
"2","(-5900,3650)","0","mstr_discrete","I162";
;
LOCATION"R6W9"
VALUE"4.75K"
PART_NUMBER"G21796-072"
PACK_TYPE"0402"
TOLERANCE"1%"
MATERIAL"EMPTY"
WATTAGE"1/16W"
CDS_LOCATION"R6W9"
CDS_LIB"mstr_discrete"
ROOM"HOT_SWAP"
NO_XNET_CONNECTION"1"
SEC"1"
SEC_TYPE"0402"
CDS_SEC"1";
"A"
$PN"1"40;
"B"
$PN"2"9;
%"RES"
"2","(-6250,3650)","0","mstr_discrete","I163";
;
MATERIAL"EMPTY"
VALUE"4.75K"
TOLERANCE"1%"
WATTAGE"1/16W"
PACK_TYPE"0402"
LOCATION"R6W8"
PART_NUMBER"G21796-072"
CDS_LOCATION"R6W8"
SEC_TYPE"0402"
SEC"1"
ROOM"HOT_SWAP"
NO_XNET_CONNECTION"1"
CDS_LIB"mstr_discrete"
CDS_SEC"1";
"A"
$PN"1"43;
"B"
$PN"2"15;
%"RES"
"2","(-6600,3650)","0","mstr_discrete","I164";
;
WATTAGE"1/16W"
TOLERANCE"1%"
LOCATION"R6W7"
VALUE"4.75K"
PACK_TYPE"0402"
MATERIAL"EMPTY"
PART_NUMBER"G21796-072"
CDS_LOCATION"R6W7"
SEC_TYPE"0402"
SEC"1"
CDS_LIB"mstr_discrete"
ROOM"HOT_SWAP"
NO_XNET_CONNECTION"1"
CDS_SEC"1";
"A"
$PN"1"44;
"B"
$PN"2"13;
%"RES"
"2","(-1750,3750)","2","mstr_discrete","I165";
;
CDS_SEC"1"
CDS_LOCATION"R6W35"
VALUE"100.0K"
TOLERANCE"1%"
WATTAGE"1/16W"
MATERIAL"CHIP"
LOCATION"R6W35"
PACK_TYPE"0402"
PART_NUMBER"G21796-010"
ROOM"HOT_SWAP"
SEC"1"
SEC_TYPE"0402"
CDS_LIB"mstr_discrete";
"A"
$PN"1"12;
"B"
$PN"2"30;
%"GND"
"1","(-6600,3450)","0","mstr_symbols","I4";
;
HDL_POWER"GND"
BODY_TYPE"PLUMBING"
SIZE"1B"
CDS_LIB"mstr_symbols"
VOLTAGE"0.0V";
"A\NAC"13;
%"P3V3_STBY"
"1","(-6600,4500)","0","mstr_symbols","I6";
;
HDL_POWER"P3V3_STBY"
BODY_TYPE"PLUMBING"
SIZE"1B"
CDS_LIB"mstr_symbols"
VOLTAGE"3.3V";
"G\NAC"14;
%"GND"
"1","(-6250,3450)","0","mstr_symbols","I7";
;
HDL_POWER"GND"
BODY_TYPE"PLUMBING"
VOLTAGE"0.0V"
CDS_LIB"mstr_symbols"
SIZE"1B";
"A\NAC"15;
%"P3V3_STBY"
"1","(-1775,2550)","0","mstr_symbols","I83";
;
HDL_POWER"P3V3_STBY"
BODY_TYPE"PLUMBING"
SIZE"1B"
CDS_LIB"mstr_symbols"
VOLTAGE"3.3V";
"G\NAC"16;
%"CAP_A"
"1","(-1775,2300)","0","dev_discrete","I85";
;
VALUE"0.1UF"
PART_NUMBER"A36096-030"
LOCATION"C6W3"
PACK_TYPE"0402V"
MATERIAL"X7R"
VOLTAGE"16V"
TOLERANCE"10%"
BOM_COST"SM_THERM"
SEC_TYPE"0402V"
SEC"1"
ROOM"TEMP_SENSORS"
CDS_SEC"1"
CDS_LIB"dev_discrete"
CDS_LOCATION"C6W3";
"B"
$PN"2"17;
"A"
$PN"1"16;
%"GND"
"1","(-1775,2050)","0","mstr_symbols","I86";
;
HDL_POWER"GND"
BODY_TYPE"PLUMBING"
SIZE"1B"
VOLTAGE"0.0V"
CDS_LIB"mstr_symbols";
"A\NAC"17;
%"RES"
"1","(-1025,1750)","0","mstr_discrete","I87";
;
CDS_SEC"1"
PACK_TYPE"0402"
VALUE"20.0"
TOLERANCE"1%"
LOCATION"R6W20"
MATERIAL"CHIP"
WATTAGE"1/16W"
PART_NUMBER"G21796-173"
CDS_LIB"mstr_discrete"
BOM_COST"SM_THERM"
ROOM"TEMP_SENSORS"
CDS_LOCATION"R6W20"
SEC_TYPE"0402"
SEC"1";
"B"
$PN"2"32;
"A"
$PN"1"21;
%"P3V3_STBY"
"1","(-3200,2500)","0","mstr_symbols","I88";
;
SIZE"1B"
VOLTAGE"3.3V"
CDS_LIB"mstr_symbols"
BODY_TYPE"PLUMBING"
HDL_POWER"P3V3_STBY";
"G\NAC"18;
%"AT24C64"
"1","(-2200,1850)","0","mstr_memory","I89";
;
CDS_SEC"1"
LOCATION"U6W3"
MATERIAL"IC"
PART_NUMBER"C47049-001"
POWER_GROUP"VCC=P3V3_STBY;GND=GND;"
CDS_LIB"mstr_memory"
ROOM"TEMP_SENSORS"
PACK_TYPE"SOICLF"
SEC_TYPE"SOICLF"
BOM_COST"SM_THERM"
SEC"1"
CDS_LOCATION"U6W3";
"SDA"
$PN"5"21;
"WP"
$PN"7"36;
"SCL"
$PN"6"35;
"A0"
$PN"1"34;
"A1"
$PN"2"19;
"A2"
$PN"3"19;
%"RES"
"2","(-3200,2200)","0","mstr_discrete","I90";
;
CDS_SEC"1"
PART_NUMBER"G21796-026"
WATTAGE"1/16W"
MATERIAL"CHIP"
PACK_TYPE"0402"
TOLERANCE"1%"
VALUE"1.00K"
LOCATION"R6W21"
CDS_LOCATION"R6W21"
ROOM"TEMP_SENSORS"
SEC"1"
BOM_COST"SM_THERM"
SEC_TYPE"0402"
CDS_LIB"mstr_discrete";
"A"
$PN"1"18;
"B"
$PN"2"34;
%"GND"
"1","(-2700,1925)","0","mstr_symbols","I91";
;
HDL_POWER"GND"
BODY_TYPE"PLUMBING"
SIZE"1B"
CDS_LIB"mstr_symbols"
VOLTAGE"0.0V";
"A\NAC"19;
%"RES"
"2","(-3200,1500)","0","mstr_discrete","I92";
;
CDS_SEC"1"
PART_NUMBER"G21796-026"
WATTAGE"1/16W"
PACK_TYPE"0402"
MATERIAL"CHIP"
LOCATION"R6W23"
VALUE"1.00K"
TOLERANCE"1%"
CDS_LIB"mstr_discrete"
SEC"1"
ROOM"TEMP_SENSORS"
BOM_COST"SM_THERM"
SEC_TYPE"0402"
CDS_LOCATION"R6W23";
"A"
$PN"1"36;
"B"
$PN"2"20;
%"GND"
"1","(-3200,1300)","0","mstr_symbols","I93";
;
HDL_POWER"GND"
BODY_TYPE"PLUMBING"
CDS_LIB"mstr_symbols"
SIZE"1B"
VOLTAGE"0.0V";
"A\NAC"20;
%"RES"
"1","(-3425,1750)","0","mstr_discrete","I94";
;
CDS_SEC"1"
PART_NUMBER"G21796-173"
MATERIAL"CHIP"
TOLERANCE"1%"
VALUE"20.0"
PACK_TYPE"0402"
WATTAGE"1/16W"
LOCATION"R6W22"
CDS_LOCATION"R6W22"
SEC"1"
CDS_LIB"mstr_discrete"
ROOM"TEMP_SENSORS"
SEC_TYPE"0402"
BOM_COST"SM_THERM";
"B"
$PN"2"35;
"A"
$PN"1"64;
%"RES"
"1","(-7350,3350)","1","mstr_discrete","I98";
;
CDS_SEC"1"
CDS_LOCATION"R6W11"
LOCATION"R6W11"
VALUE"4.75K"
WATTAGE"1/16W"
MATERIAL"CHIP"
PART_NUMBER"G21796-072"
PACK_TYPE"0402"
TOLERANCE"1%"
SEC"1"
SEC_TYPE"0402"
CDS_LIB"mstr_discrete";
"B"
$PN"2"7;
"A"
$PN"1"54;
%"RES"
"1","(-7050,3350)","1","mstr_discrete","I99";
;
CDS_SEC"1"
CDS_LOCATION"R6W12"
MATERIAL"CHIP"
PART_NUMBER"G21796-072"
TOLERANCE"1%"
WATTAGE"1/16W"
PACK_TYPE"0402"
VALUE"4.75K"
LOCATION"R6W12"
CDS_LIB"mstr_discrete"
SEC_TYPE"0402"
SEC"1";
"B"
$PN"2"7;
"A"
$PN"1"55;
END.
